(kicad_pcb
	(version 20260206)
	(generator "pcbnew")
	(generator_version "10.0")
	(general
		(thickness 1.6)
		(legacy_teardrops no)
	)
	(paper "A4")
	(title_block
		(title "12092022_DA0F0TMDCD0_F0T_Management_Board_D_brd_V3_OCP.brd")
		(comment 1 "Grand Teton / footprints 281-287 of 1440")
	)
	(layers
		(0 "F.Cu" signal "TOP")
		(4 "In1.Cu" signal "GND")
		(6 "In2.Cu" signal "IN1")
		(8 "In3.Cu" signal "GND1")
		(10 "In4.Cu" signal "IN2")
		(12 "In5.Cu" signal "VCC")
		(14 "In6.Cu" signal "VCC1")
		(16 "In7.Cu" signal "IN3")
		(18 "In8.Cu" signal "GND2")
		(20 "In9.Cu" signal "IN4")
		(22 "In10.Cu" signal "GND3")
		(2 "B.Cu" signal "BOTTOM")
		(9 "F.Adhes" user "F.Adhesive")
		(11 "B.Adhes" user "B.Adhesive")
		(13 "F.Paste" user "Package Geometry/Pastemask Top")
		(15 "B.Paste" user "Package Geometry/Pastemask Bottom")
		(5 "F.SilkS" user "Ref Des/Silkscreen Top")
		(7 "B.SilkS" user "Ref Des/Silkscreen Bottom")
		(1 "F.Mask" user "Board Geometry/Soldermask Top")
		(3 "B.Mask" user "Board Geometry/Soldermask Bottom")
		(17 "Dwgs.User" user "User.Drawings")
		(19 "Cmts.User" user "User.Comments")
		(21 "Eco1.User" user "User.Eco1")
		(23 "Eco2.User" user "User.Eco2")
		(25 "Edge.Cuts" user "Board Geometry/Outline")
		(27 "Margin" user)
		(31 "F.CrtYd" user "Package Geometry/Place Bound Top")
		(29 "B.CrtYd" user "Package Geometry/Place Bound Bottom")
		(35 "F.Fab" user "Ref Des/Assembly Top")
		(33 "B.Fab" user "Ref Des/Assembly Bottom")
	)
	(footprint ""
		(layer "F.Cu")
		(at 28.829 -13.081)
		(property "Reference" "U9"
			(at -2.38633 -0.254 90)
			(unlocked yes)
			(layer "F.SilkS")
			(effects
				(font
					(size 0.7874 0.5842)
					(thickness 0.1524)
				)
			)
		)
		(property "Value" ""
			(at 0 0 0)
			(layer "F.Fab")
			(effects
				(font
					(size 1.27 1.27)
				)
			)
		)
		(duplicate_pad_numbers_are_jumpers no)
		(fp_line
			(start -1.834896 -1.575054)
			(end -0.508 -1.575054)
			(stroke
				(width 0.1524)
				(type default)
			)
			(layer "F.SilkS")
		)
		(fp_line
			(start -1.834896 1.575054)
			(end -1.834896 -1.575054)
			(stroke
				(width 0.1524)
				(type default)
			)
			(layer "F.SilkS")
		)
		(fp_line
			(start -0.508 -1.575054)
			(end 0 -1.016)
			(stroke
				(width 0.1524)
				(type default)
			)
			(layer "F.SilkS")
		)
		(fp_line
			(start 0 -1.016)
			(end 0.508 -1.575054)
			(stroke
				(width 0.1524)
				(type default)
			)
			(layer "F.SilkS")
		)
		(fp_line
			(start 0.508 -1.575054)
			(end 1.834896 -1.575054)
			(stroke
				(width 0.1524)
				(type default)
			)
			(layer "F.SilkS")
		)
		(fp_line
			(start 1.834896 -1.575054)
			(end 1.834896 1.575054)
			(stroke
				(width 0.1524)
				(type default)
			)
			(layer "F.SilkS")
		)
		(fp_line
			(start 1.834896 1.575054)
			(end -1.834896 1.575054)
			(stroke
				(width 0.1524)
				(type default)
			)
			(layer "F.SilkS")
		)
		(fp_poly
			(pts
				(xy -2.372614 -2.627884) (xy -3.09118 -1.909318) (xy -2.013458 -1.550162)
			)
			(stroke
				(width 0)
				(type default)
			)
			(fill yes)
			(layer "F.SilkS")
		)
		(fp_line
			(start -0.824992 -1.575054)
			(end 0.824992 -1.575054)
			(stroke
				(width 0.1)
				(type default)
			)
			(layer "F.Fab")
		)
		(fp_line
			(start -0.824992 1.575054)
			(end -0.824992 -1.575054)
			(stroke
				(width 0.1)
				(type default)
			)
			(layer "F.Fab")
		)
		(fp_line
			(start 0.824992 -1.575054)
			(end 0.824992 1.575054)
			(stroke
				(width 0.1)
				(type default)
			)
			(layer "F.Fab")
		)
		(fp_line
			(start 0.824992 1.575054)
			(end -0.824992 1.575054)
			(stroke
				(width 0.1)
				(type default)
			)
			(layer "F.Fab")
		)
		(fp_poly
			(pts
				(xy -3.003296 -1.45796) (xy -3.003296 -0.44196) (xy -1.987296 -0.94996)
			)
			(stroke
				(width 0)
				(type default)
			)
			(fill yes)
			(layer "F.Fab")
		)
		(pad "1" smd rect
			(at -1.199896 -0.94996 270)
			(size 0.7112 1.016)
			(layers "F.Cu" "F.Mask" "F.Paste")
			(net "BEEP_LED")
		)
		(pad "2" smd rect
			(at -1.199896 0 270)
			(size 0.7112 1.016)
			(layers "F.Cu" "F.Mask" "F.Paste")
			(net "FM_ID_R_LED")
		)
		(pad "3" smd rect
			(at -1.199896 0.94996 270)
			(size 0.7112 1.016)
			(layers "F.Cu" "F.Mask" "F.Paste")
			(net "GND")
		)
		(pad "4" smd rect
			(at 1.199896 0.94996 270)
			(size 0.7112 1.016)
			(layers "F.Cu" "F.Mask" "F.Paste")
			(net "ID_LED_BUF")
		)
		(pad "5" smd rect
			(at 1.199896 -0.94996 270)
			(size 0.7112 1.016)
			(layers "F.Cu" "F.Mask" "F.Paste")
			(net "P3V3_AUX")
		)
	)
	(footprint ""
		(layer "F.Cu")
		(at 38.989 -58.547 -90)
		(property "Reference" "R275"
			(at 0 0 270)
			(layer "F.SilkS")
			(hide yes)
			(effects
				(font
					(size 1.27 1.27)
				)
			)
		)
		(property "Value" ""
			(at 0 0 270)
			(layer "F.Fab")
			(effects
				(font
					(size 1.27 1.27)
				)
			)
		)
		(duplicate_pad_numbers_are_jumpers no)
		(fp_line
			(start -0.7874 0.4064)
			(end -0.7874 -0.4064)
			(stroke
				(width 0.1524)
				(type default)
			)
			(layer "F.SilkS")
		)
		(fp_line
			(start 0.7874 0.4064)
			(end -0.7874 0.4064)
			(stroke
				(width 0.1524)
				(type default)
			)
			(layer "F.SilkS")
		)
		(fp_line
			(start -0.7874 -0.4064)
			(end 0.7874 -0.4064)
			(stroke
				(width 0.1524)
				(type default)
			)
			(layer "F.SilkS")
		)
		(fp_line
			(start 0.7874 -0.4064)
			(end 0.7874 0.4064)
			(stroke
				(width 0.1524)
				(type default)
			)
			(layer "F.SilkS")
		)
		(fp_line
			(start -0.67945 0.3048)
			(end -0.67945 -0.305054)
			(stroke
				(width 0.1)
				(type default)
			)
			(layer "F.Fab")
		)
		(fp_line
			(start -0.12065 0.3048)
			(end -0.67945 0.3048)
			(stroke
				(width 0.1)
				(type default)
			)
			(layer "F.Fab")
		)
		(fp_line
			(start 0.120396 0.3048)
			(end 0.120396 0.2794)
			(stroke
				(width 0.1)
				(type default)
			)
			(layer "F.Fab")
		)
		(fp_line
			(start 0.67945 0.3048)
			(end 0.120396 0.3048)
			(stroke
				(width 0.1)
				(type default)
			)
			(layer "F.Fab")
		)
		(fp_line
			(start -0.12065 0.2794)
			(end -0.12065 0.3048)
			(stroke
				(width 0.1)
				(type default)
			)
			(layer "F.Fab")
		)
		(fp_line
			(start 0.120396 0.2794)
			(end -0.12065 0.2794)
			(stroke
				(width 0.1)
				(type default)
			)
			(layer "F.Fab")
		)
		(fp_line
			(start -0.12065 -0.2794)
			(end 0.12065 -0.2794)
			(stroke
				(width 0.1)
				(type default)
			)
			(layer "F.Fab")
		)
		(fp_line
			(start 0.12065 -0.2794)
			(end 0.12065 -0.3048)
			(stroke
				(width 0.1)
				(type default)
			)
			(layer "F.Fab")
		)
		(fp_line
			(start 0.12065 -0.3048)
			(end 0.67945 -0.3048)
			(stroke
				(width 0.1)
				(type default)
			)
			(layer "F.Fab")
		)
		(fp_line
			(start 0.67945 -0.3048)
			(end 0.67945 0.3048)
			(stroke
				(width 0.1)
				(type default)
			)
			(layer "F.Fab")
		)
		(fp_line
			(start -0.67945 -0.305054)
			(end -0.12065 -0.305054)
			(stroke
				(width 0.1)
				(type default)
			)
			(layer "F.Fab")
		)
		(fp_line
			(start -0.12065 -0.305054)
			(end -0.12065 -0.2794)
			(stroke
				(width 0.1)
				(type default)
			)
			(layer "F.Fab")
		)
		(pad "1" smd circle
			(at -0.40005 0 270)
			(size 0 0)
			(layers "F.Cu" "F.Mask" "F.Paste")
			(net "PWRGD_P1V8_AUX")
		)
		(pad "2" smd circle
			(at 0.40005 0 270)
			(size 0 0)
			(layers "F.Cu" "F.Mask" "F.Paste")
			(net "PWRGD_P1V8_AUX_R")
		)
	)
	(footprint ""
		(layer "F.Cu")
		(at 12.319 -87.376 180)
		(property "Reference" "R691"
			(at 0 0 180)
			(layer "F.SilkS")
			(hide yes)
			(effects
				(font
					(size 1.27 1.27)
				)
			)
		)
		(property "Value" ""
			(at 0 0 180)
			(layer "F.Fab")
			(effects
				(font
					(size 1.27 1.27)
				)
			)
		)
		(duplicate_pad_numbers_are_jumpers no)
		(fp_line
			(start 0.7874 0.4064)
			(end -0.7874 0.4064)
			(stroke
				(width 0.1524)
				(type default)
			)
			(layer "F.SilkS")
		)
		(fp_line
			(start 0.7874 -0.4064)
			(end 0.7874 0.4064)
			(stroke
				(width 0.1524)
				(type default)
			)
			(layer "F.SilkS")
		)
		(fp_line
			(start -0.7874 0.4064)
			(end -0.7874 -0.4064)
			(stroke
				(width 0.1524)
				(type default)
			)
			(layer "F.SilkS")
		)
		(fp_line
			(start -0.7874 -0.4064)
			(end 0.7874 -0.4064)
			(stroke
				(width 0.1524)
				(type default)
			)
			(layer "F.SilkS")
		)
		(fp_line
			(start 0.67945 0.3048)
			(end 0.120396 0.3048)
			(stroke
				(width 0.1)
				(type default)
			)
			(layer "F.Fab")
		)
		(fp_line
			(start 0.67945 -0.3048)
			(end 0.67945 0.3048)
			(stroke
				(width 0.1)
				(type default)
			)
			(layer "F.Fab")
		)
		(fp_line
			(start 0.12065 -0.2794)
			(end 0.12065 -0.3048)
			(stroke
				(width 0.1)
				(type default)
			)
			(layer "F.Fab")
		)
		(fp_line
			(start 0.12065 -0.3048)
			(end 0.67945 -0.3048)
			(stroke
				(width 0.1)
				(type default)
			)
			(layer "F.Fab")
		)
		(fp_line
			(start 0.120396 0.3048)
			(end 0.120396 0.2794)
			(stroke
				(width 0.1)
				(type default)
			)
			(layer "F.Fab")
		)
		(fp_line
			(start 0.120396 0.2794)
			(end -0.12065 0.2794)
			(stroke
				(width 0.1)
				(type default)
			)
			(layer "F.Fab")
		)
		(fp_line
			(start -0.12065 0.3048)
			(end -0.67945 0.3048)
			(stroke
				(width 0.1)
				(type default)
			)
			(layer "F.Fab")
		)
		(fp_line
			(start -0.12065 0.2794)
			(end -0.12065 0.3048)
			(stroke
				(width 0.1)
				(type default)
			)
			(layer "F.Fab")
		)
		(fp_line
			(start -0.12065 -0.2794)
			(end 0.12065 -0.2794)
			(stroke
				(width 0.1)
				(type default)
			)
			(layer "F.Fab")
		)
		(fp_line
			(start -0.12065 -0.305054)
			(end -0.12065 -0.2794)
			(stroke
				(width 0.1)
				(type default)
			)
			(layer "F.Fab")
		)
		(fp_line
			(start -0.67945 0.3048)
			(end -0.67945 -0.305054)
			(stroke
				(width 0.1)
				(type default)
			)
			(layer "F.Fab")
		)
		(fp_line
			(start -0.67945 -0.305054)
			(end -0.12065 -0.305054)
			(stroke
				(width 0.1)
				(type default)
			)
			(layer "F.Fab")
		)
		(pad "1" smd circle
			(at -0.40005 0 180)
			(size 0 0)
			(layers "F.Cu" "F.Mask" "F.Paste")
			(net "RST_SGPIO_RESET_R_N")
		)
		(pad "2" smd circle
			(at 0.40005 0 180)
			(size 0 0)
			(layers "F.Cu" "F.Mask" "F.Paste")
			(net "RST_SGPIO_RESET_N")
		)
	)
	(footprint ""
		(layer "F.Cu")
		(at 39.9288 -43.434)
		(property "Reference" "R266"
			(at 0 0 0)
			(layer "F.SilkS")
			(hide yes)
			(effects
				(font
					(size 1.27 1.27)
				)
			)
		)
		(property "Value" ""
			(at 0 0 0)
			(layer "F.Fab")
			(effects
				(font
					(size 1.27 1.27)
				)
			)
		)
		(duplicate_pad_numbers_are_jumpers no)
		(fp_line
			(start -0.7874 -0.4064)
			(end 0.7874 -0.4064)
			(stroke
				(width 0.1524)
				(type default)
			)
			(layer "F.SilkS")
		)
		(fp_line
			(start -0.7874 0.4064)
			(end -0.7874 -0.4064)
			(stroke
				(width 0.1524)
				(type default)
			)
			(layer "F.SilkS")
		)
		(fp_line
			(start 0.7874 -0.4064)
			(end 0.7874 0.4064)
			(stroke
				(width 0.1524)
				(type default)
			)
			(layer "F.SilkS")
		)
		(fp_line
			(start 0.7874 0.4064)
			(end -0.7874 0.4064)
			(stroke
				(width 0.1524)
				(type default)
			)
			(layer "F.SilkS")
		)
		(fp_line
			(start -0.67945 -0.305054)
			(end -0.12065 -0.305054)
			(stroke
				(width 0.1)
				(type default)
			)
			(layer "F.Fab")
		)
		(fp_line
			(start -0.67945 0.3048)
			(end -0.67945 -0.305054)
			(stroke
				(width 0.1)
				(type default)
			)
			(layer "F.Fab")
		)
		(fp_line
			(start -0.12065 -0.305054)
			(end -0.12065 -0.2794)
			(stroke
				(width 0.1)
				(type default)
			)
			(layer "F.Fab")
		)
		(fp_line
			(start -0.12065 -0.2794)
			(end 0.12065 -0.2794)
			(stroke
				(width 0.1)
				(type default)
			)
			(layer "F.Fab")
		)
		(fp_line
			(start -0.12065 0.2794)
			(end -0.12065 0.3048)
			(stroke
				(width 0.1)
				(type default)
			)
			(layer "F.Fab")
		)
		(fp_line
			(start -0.12065 0.3048)
			(end -0.67945 0.3048)
			(stroke
				(width 0.1)
				(type default)
			)
			(layer "F.Fab")
		)
		(fp_line
			(start 0.120396 0.2794)
			(end -0.12065 0.2794)
			(stroke
				(width 0.1)
				(type default)
			)
			(layer "F.Fab")
		)
		(fp_line
			(start 0.120396 0.3048)
			(end 0.120396 0.2794)
			(stroke
				(width 0.1)
				(type default)
			)
			(layer "F.Fab")
		)
		(fp_line
			(start 0.12065 -0.3048)
			(end 0.67945 -0.3048)
			(stroke
				(width 0.1)
				(type default)
			)
			(layer "F.Fab")
		)
		(fp_line
			(start 0.12065 -0.2794)
			(end 0.12065 -0.3048)
			(stroke
				(width 0.1)
				(type default)
			)
			(layer "F.Fab")
		)
		(fp_line
			(start 0.67945 -0.3048)
			(end 0.67945 0.3048)
			(stroke
				(width 0.1)
				(type default)
			)
			(layer "F.Fab")
		)
		(fp_line
			(start 0.67945 0.3048)
			(end 0.120396 0.3048)
			(stroke
				(width 0.1)
				(type default)
			)
			(layer "F.Fab")
		)
		(pad "1" smd circle
			(at -0.40005 0)
			(size 0 0)
			(layers "F.Cu" "F.Mask" "F.Paste")
			(net "P3V3_AUX")
		)
		(pad "2" smd circle
			(at 0.40005 0)
			(size 0 0)
			(layers "F.Cu" "F.Mask" "F.Paste")
			(net "FM_ME_BT_DONE")
		)
	)
	(footprint ""
		(layer "F.Cu")
		(at 31.70809 -16.503396 90)
		(property "Reference" "U38"
			(at -2.052066 1.69291 0)
			(unlocked yes)
			(layer "F.SilkS")
			(effects
				(font
					(size 0.7874 0.5842)
					(thickness 0.1524)
				)
				(justify left)
			)
		)
		(property "Value" ""
			(at 0 0 90)
			(layer "F.Fab")
			(effects
				(font
					(size 1.27 1.27)
				)
			)
		)
		(duplicate_pad_numbers_are_jumpers no)
		(fp_line
			(start 0.517398 -1.500124)
			(end 0.517398 0.122936)
			(stroke
				(width 0.1524)
				(type default)
			)
			(layer "F.SilkS")
		)
		(fp_line
			(start 0.374904 -1.500124)
			(end 0.517398 -1.500124)
			(stroke
				(width 0.1524)
				(type default)
			)
			(layer "F.SilkS")
		)
		(fp_line
			(start -0.517398 -1.500124)
			(end -0.336296 -1.500124)
			(stroke
				(width 0.1524)
				(type default)
			)
			(layer "F.SilkS")
		)
		(fp_line
			(start -0.517398 0.128016)
			(end -0.517398 -1.500124)
			(stroke
				(width 0.1524)
				(type default)
			)
			(layer "F.SilkS")
		)
		(fp_poly
			(pts
				(xy -1.5875 -0.621284) (xy -2.2225 -0.938784) (xy -2.2225 -0.303784)
			)
			(stroke
				(width 0)
				(type default)
			)
			(fill yes)
			(layer "F.SilkS")
		)
		(fp_line
			(start 0.700024 -1.500124)
			(end 0.700024 1.500124)
			(stroke
				(width 0.1)
				(type default)
			)
			(layer "F.Fab")
		)
		(fp_line
			(start -0.700024 -1.500124)
			(end 0.700024 -1.500124)
			(stroke
				(width 0.1)
				(type default)
			)
			(layer "F.Fab")
		)
		(fp_line
			(start 0.700024 1.500124)
			(end -0.700024 1.500124)
			(stroke
				(width 0.1)
				(type default)
			)
			(layer "F.Fab")
		)
		(fp_line
			(start -0.700024 1.500124)
			(end -0.700024 -1.500124)
			(stroke
				(width 0.1)
				(type default)
			)
			(layer "F.Fab")
		)
		(fp_poly
			(pts
				(xy -1.5113 -0.750062) (xy -2.1463 -1.067562) (xy -2.1463 -0.432562)
			)
			(stroke
				(width 0)
				(type default)
			)
			(fill yes)
			(layer "F.Fab")
		)
		(pad "1" smd rect
			(at -0.999998 -0.750062 90)
			(size 0.7112 1.016)
			(layers "F.Cu" "F.Mask" "F.Paste")
			(net "GND")
		)
		(pad "2" smd rect
			(at -0.999998 0.94996)
			(size 0.6096 0.7112)
			(layers "F.Cu" "F.Mask" "F.Paste")
			(net "USB2_01_F_DP")
		)
		(pad "3" smd rect
			(at 0.999998 0.94996)
			(size 0.6096 0.7112)
			(layers "F.Cu" "F.Mask" "F.Paste")
			(net "USB2_01_F_DN")
		)
		(pad "4" smd rect
			(at 0.999998 -0.94996)
			(size 0.6096 0.7112)
			(layers "F.Cu" "F.Mask" "F.Paste")
			(net "P5V_USB_REAR")
		)
	)
	(footprint ""
		(layer "F.Cu")
		(at 19.308826 -34.509964 180)
		(property "Reference" "PC263"
			(at 0 0 180)
			(layer "F.SilkS")
			(hide yes)
			(effects
				(font
					(size 1.27 1.27)
				)
			)
		)
		(property "Value" ""
			(at 0 0 180)
			(layer "F.Fab")
			(effects
				(font
					(size 1.27 1.27)
				)
			)
		)
		(duplicate_pad_numbers_are_jumpers no)
		(fp_line
			(start 0.7874 0.4064)
			(end -0.7874 0.4064)
			(stroke
				(width 0.1524)
				(type default)
			)
			(layer "F.SilkS")
		)
		(fp_line
			(start 0.7874 -0.4064)
			(end 0.7874 0.4064)
			(stroke
				(width 0.1524)
				(type default)
			)
			(layer "F.SilkS")
		)
		(fp_line
			(start -0.7874 0.4064)
			(end -0.7874 -0.4064)
			(stroke
				(width 0.1524)
				(type default)
			)
			(layer "F.SilkS")
		)
		(fp_line
			(start -0.7874 -0.4064)
			(end 0.7874 -0.4064)
			(stroke
				(width 0.1524)
				(type default)
			)
			(layer "F.SilkS")
		)
		(fp_line
			(start 0.67945 0.3048)
			(end 0.120396 0.3048)
			(stroke
				(width 0.1)
				(type default)
			)
			(layer "F.Fab")
		)
		(fp_line
			(start 0.67945 -0.3048)
			(end 0.67945 0.3048)
			(stroke
				(width 0.1)
				(type default)
			)
			(layer "F.Fab")
		)
		(fp_line
			(start 0.12065 -0.2794)
			(end 0.12065 -0.3048)
			(stroke
				(width 0.1)
				(type default)
			)
			(layer "F.Fab")
		)
		(fp_line
			(start 0.12065 -0.3048)
			(end 0.67945 -0.3048)
			(stroke
				(width 0.1)
				(type default)
			)
			(layer "F.Fab")
		)
		(fp_line
			(start 0.120396 0.3048)
			(end 0.120396 0.2794)
			(stroke
				(width 0.1)
				(type default)
			)
			(layer "F.Fab")
		)
		(fp_line
			(start 0.120396 0.2794)
			(end -0.12065 0.2794)
			(stroke
				(width 0.1)
				(type default)
			)
			(layer "F.Fab")
		)
		(fp_line
			(start -0.12065 0.3048)
			(end -0.67945 0.3048)
			(stroke
				(width 0.1)
				(type default)
			)
			(layer "F.Fab")
		)
		(fp_line
			(start -0.12065 0.2794)
			(end -0.12065 0.3048)
			(stroke
				(width 0.1)
				(type default)
			)
			(layer "F.Fab")
		)
		(fp_line
			(start -0.12065 -0.2794)
			(end 0.12065 -0.2794)
			(stroke
				(width 0.1)
				(type default)
			)
			(layer "F.Fab")
		)
		(fp_line
			(start -0.12065 -0.305054)
			(end -0.12065 -0.2794)
			(stroke
				(width 0.1)
				(type default)
			)
			(layer "F.Fab")
		)
		(fp_line
			(start -0.67945 0.3048)
			(end -0.67945 -0.305054)
			(stroke
				(width 0.1)
				(type default)
			)
			(layer "F.Fab")
		)
		(fp_line
			(start -0.67945 -0.305054)
			(end -0.12065 -0.305054)
			(stroke
				(width 0.1)
				(type default)
			)
			(layer "F.Fab")
		)
		(pad "1" smd circle
			(at -0.40005 0 180)
			(size 0 0)
			(layers "F.Cu" "F.Mask" "F.Paste")
			(net "SW_P1V0_AUX_FLT")
		)
		(pad "2" smd circle
			(at 0.40005 0 180)
			(size 0 0)
			(layers "F.Cu" "F.Mask" "F.Paste")
			(net "GND")
		)
	)
	(footprint ""
		(layer "F.Cu")
		(at 84.700364 -11.789918)
		(property "Reference" "H7"
			(at -4.842764 -2.280412 0)
			(unlocked yes)
			(layer "F.SilkS")
			(effects
				(font
					(size 0.7874 0.5842)
					(thickness 0.1524)
				)
				(justify left)
			)
		)
		(property "Value" ""
			(at 0 0 0)
			(layer "F.Fab")
			(effects
				(font
					(size 1.27 1.27)
				)
			)
		)
		(duplicate_pad_numbers_are_jumpers no)
		(pad "1" thru_hole circle
			(at 0 0)
			(size 6.5024 6.5024)
			(drill 3.2004)
			(layers "*.Cu" "*.Mask")
			(remove_unused_layers no)
			(net "GND")
			(clearance -1.397)
		)
	)
)
